# S9S_MB_2U (Grand Teton) — schematic netlist excerpt (pin names and nets, part order shuffled) for the footprints in the layout excerpt that follows; sources: Cadence DE-HDL packaged netlist, KiCad conversion of 03242023_DA0F0TMBIJ0_F0T_Motherboard_J_brd_V01_OCP.brd

C499  Q_CAP  47UF 4V 20% X6S  pkg C0805  page 76 : A = PVCCD_HV_CPU0 ; B = GND
C2325  Q_CAP  0.1UF 25V 10% EMPTY  pkg 0402  page 196 : A = PD_USB_HUB_2_VREG ; B = GND
R961  Q_RES  33.2 1% CHIP  pkg 0402LF  page 235 : A = SMB_PEHPCPU1_GTL_SCL ; B = SMB_PEHPCPU1_GTL_R_SCL

(kicad_pcb
	(version 20260206)
	(generator "pcbnew")
	(generator_version "10.0")
	(general
		(thickness 1.6)
		(legacy_teardrops no)
	)
	(paper "A4")
	(title_block
		(title "03242023_DA0F0TMBIJ0_F0T_Motherboard_J_brd_V01_OCP.brd")
		(comment 1 "Grand Teton / footprints 4966-4968 of 6105")
	)
	(layers
		(0 "F.Cu" signal "TOP")
		(4 "In1.Cu" signal "GND")
		(6 "In2.Cu" signal "IN1")
		(8 "In3.Cu" signal "GND1")
		(10 "In4.Cu" signal "IN2")
		(12 "In5.Cu" signal "GND2")
		(14 "In6.Cu" signal "IN3")
		(16 "In7.Cu" signal "GND3")
		(18 "In8.Cu" signal "VCC")
		(20 "In9.Cu" signal "VCC1")
		(22 "In10.Cu" signal "GND4")
		(24 "In11.Cu" signal "IN4")
		(26 "In12.Cu" signal "GND5")
		(28 "In13.Cu" signal "IN5")
		(30 "In14.Cu" signal "GND6")
		(32 "In15.Cu" signal "IN6")
		(34 "In16.Cu" signal "GND7")
		(2 "B.Cu" signal "BOTTOM")
		(9 "F.Adhes" user "F.Adhesive")
		(11 "B.Adhes" user "B.Adhesive")
		(13 "F.Paste" user "Package Geometry/Pastemask Top")
		(15 "B.Paste" user "Package Geometry/Pastemask Bottom")
		(5 "F.SilkS" user "Ref Des/Silkscreen Top")
		(7 "B.SilkS" user "Ref Des/Silkscreen Bottom")
		(1 "F.Mask" user "Board Geometry/Soldermask Top")
		(3 "B.Mask" user "Board Geometry/Soldermask Bottom")
		(17 "Dwgs.User" user "User.Drawings")
		(19 "Cmts.User" user "User.Comments")
		(21 "Eco1.User" user "User.Eco1")
		(23 "Eco2.User" user "User.Eco2")
		(25 "Edge.Cuts" user "Board Geometry/Outline")
		(27 "Margin" user)
		(31 "F.CrtYd" user "Package Geometry/Place Bound Top")
		(29 "B.CrtYd" user "Package Geometry/Place Bound Bottom")
		(35 "F.Fab" user "Ref Des/Assembly Top")
		(33 "B.Fab" user "Ref Des/Assembly Bottom")
	)
	(footprint ""
		(layer "B.Cu")
		(at 359.24998 -212.049614)
		(property "Reference" "C499"
			(at 0 0 0)
			(layer "B.SilkS")
			(hide yes)
			(effects
				(font
					(size 1.27 1.27)
				)
				(justify mirror)
			)
		)
		(property "Value" ""
			(at 0 0 0)
			(layer "B.Fab")
			(effects
				(font
					(size 1.27 1.27)
				)
				(justify mirror)
			)
		)
		(duplicate_pad_numbers_are_jumpers no)
		(fp_line
			(start -1.524 -0.762)
			(end -1.524 0.762)
			(stroke
				(width 0.1524)
				(type default)
			)
			(layer "B.SilkS")
		)
		(fp_line
			(start -1.524 0.762)
			(end 1.524 0.762)
			(stroke
				(width 0.1524)
				(type default)
			)
			(layer "B.SilkS")
		)
		(fp_line
			(start 1.524 -0.762)
			(end -1.524 -0.762)
			(stroke
				(width 0.1524)
				(type default)
			)
			(layer "B.SilkS")
		)
		(fp_line
			(start 1.524 0.762)
			(end 1.524 -0.762)
			(stroke
				(width 0.1524)
				(type default)
			)
			(layer "B.SilkS")
		)
		(fp_line
			(start -1.1049 -0.724916)
			(end 1.1049 -0.724916)
			(stroke
				(width 0.1)
				(type default)
			)
			(layer "B.Fab")
		)
		(fp_line
			(start -1.1049 0.724916)
			(end -1.1049 -0.724916)
			(stroke
				(width 0.1)
				(type default)
			)
			(layer "B.Fab")
		)
		(fp_line
			(start 1.1049 -0.724916)
			(end 1.1049 0.724916)
			(stroke
				(width 0.1)
				(type default)
			)
			(layer "B.Fab")
		)
		(fp_line
			(start 1.1049 0.724916)
			(end -1.1049 0.724916)
			(stroke
				(width 0.1)
				(type default)
			)
			(layer "B.Fab")
		)
		(pad "1" smd rect
			(at 0.889 0)
			(size 1.016 1.27)
			(layers "B.Cu" "B.Mask" "B.Paste")
			(net "PVCCD_HV_CPU0")
		)
		(pad "2" smd rect
			(at -0.889 0)
			(size 1.016 1.27)
			(layers "B.Cu" "B.Mask" "B.Paste")
			(net "GND")
		)
	)
	(footprint ""
		(layer "B.Cu")
		(at 136.60755 -28.598368)
		(property "Reference" "C2325"
			(at 0 0 0)
			(layer "B.SilkS")
			(hide yes)
			(effects
				(font
					(size 1.27 1.27)
				)
				(justify mirror)
			)
		)
		(property "Value" ""
			(at 0 0 0)
			(layer "B.Fab")
			(effects
				(font
					(size 1.27 1.27)
				)
				(justify mirror)
			)
		)
		(duplicate_pad_numbers_are_jumpers no)
		(fp_line
			(start -0.7874 -0.4064)
			(end -0.7874 0.4064)
			(stroke
				(width 0.1524)
				(type default)
			)
			(layer "B.SilkS")
		)
		(fp_line
			(start -0.7874 0.4064)
			(end 0.7874 0.4064)
			(stroke
				(width 0.1524)
				(type default)
			)
			(layer "B.SilkS")
		)
		(fp_line
			(start 0.7874 -0.4064)
			(end -0.7874 -0.4064)
			(stroke
				(width 0.1524)
				(type default)
			)
			(layer "B.SilkS")
		)
		(fp_line
			(start 0.7874 0.4064)
			(end 0.7874 -0.4064)
			(stroke
				(width 0.1524)
				(type default)
			)
			(layer "B.SilkS")
		)
		(fp_line
			(start -0.67945 -0.3048)
			(end -0.67945 0.3048)
			(stroke
				(width 0.1)
				(type default)
			)
			(layer "B.Fab")
		)
		(fp_line
			(start -0.67945 0.3048)
			(end -0.120396 0.3048)
			(stroke
				(width 0.1)
				(type default)
			)
			(layer "B.Fab")
		)
		(fp_line
			(start -0.12065 -0.3048)
			(end -0.67945 -0.3048)
			(stroke
				(width 0.1)
				(type default)
			)
			(layer "B.Fab")
		)
		(fp_line
			(start -0.12065 -0.2794)
			(end -0.12065 -0.3048)
			(stroke
				(width 0.1)
				(type default)
			)
			(layer "B.Fab")
		)
		(fp_line
			(start -0.120396 0.2794)
			(end 0.12065 0.2794)
			(stroke
				(width 0.1)
				(type default)
			)
			(layer "B.Fab")
		)
		(fp_line
			(start -0.120396 0.3048)
			(end -0.120396 0.2794)
			(stroke
				(width 0.1)
				(type default)
			)
			(layer "B.Fab")
		)
		(fp_line
			(start 0.12065 -0.305054)
			(end 0.12065 -0.2794)
			(stroke
				(width 0.1)
				(type default)
			)
			(layer "B.Fab")
		)
		(fp_line
			(start 0.12065 -0.2794)
			(end -0.12065 -0.2794)
			(stroke
				(width 0.1)
				(type default)
			)
			(layer "B.Fab")
		)
		(fp_line
			(start 0.12065 0.2794)
			(end 0.12065 0.3048)
			(stroke
				(width 0.1)
				(type default)
			)
			(layer "B.Fab")
		)
		(fp_line
			(start 0.12065 0.3048)
			(end 0.67945 0.3048)
			(stroke
				(width 0.1)
				(type default)
			)
			(layer "B.Fab")
		)
		(fp_line
			(start 0.67945 -0.305054)
			(end 0.12065 -0.305054)
			(stroke
				(width 0.1)
				(type default)
			)
			(layer "B.Fab")
		)
		(fp_line
			(start 0.67945 0.3048)
			(end 0.67945 -0.305054)
			(stroke
				(width 0.1)
				(type default)
			)
			(layer "B.Fab")
		)
		(pad "1" smd circle
			(at 0.40005 0 180)
			(size 0 0)
			(layers "B.Cu" "B.Mask" "B.Paste")
			(net "PD_USB_HUB_2_VREG")
		)
		(pad "2" smd circle
			(at -0.40005 0 180)
			(size 0 0)
			(layers "B.Cu" "B.Mask" "B.Paste")
			(net "GND")
		)
	)
	(footprint ""
		(layer "B.Cu")
		(at 154.21102 -226.406456 180)
		(property "Reference" "R961"
			(at 0 0 0)
			(layer "B.SilkS")
			(hide yes)
			(effects
				(font
					(size 1.27 1.27)
				)
				(justify mirror)
			)
		)
		(property "Value" ""
			(at 0 0 0)
			(layer "B.Fab")
			(effects
				(font
					(size 1.27 1.27)
				)
				(justify mirror)
			)
		)
		(duplicate_pad_numbers_are_jumpers no)
		(fp_line
			(start 0.7874 0.4064)
			(end 0.7874 -0.4064)
			(stroke
				(width 0.1524)
				(type default)
			)
			(layer "B.SilkS")
		)
		(fp_line
			(start 0.7874 -0.4064)
			(end -0.7874 -0.4064)
			(stroke
				(width 0.1524)
				(type default)
			)
			(layer "B.SilkS")
		)
		(fp_line
			(start -0.7874 0.4064)
			(end 0.7874 0.4064)
			(stroke
				(width 0.1524)
				(type default)
			)
			(layer "B.SilkS")
		)
		(fp_line
			(start -0.7874 -0.4064)
			(end -0.7874 0.4064)
			(stroke
				(width 0.1524)
				(type default)
			)
			(layer "B.SilkS")
		)
		(fp_line
			(start 0.67945 0.3048)
			(end 0.67945 -0.305054)
			(stroke
				(width 0.1)
				(type default)
			)
			(layer "B.Fab")
		)
		(fp_line
			(start 0.67945 -0.305054)
			(end 0.12065 -0.305054)
			(stroke
				(width 0.1)
				(type default)
			)
			(layer "B.Fab")
		)
		(fp_line
			(start 0.12065 0.3048)
			(end 0.67945 0.3048)
			(stroke
				(width 0.1)
				(type default)
			)
			(layer "B.Fab")
		)
		(fp_line
			(start 0.12065 0.2794)
			(end 0.12065 0.3048)
			(stroke
				(width 0.1)
				(type default)
			)
			(layer "B.Fab")
		)
		(fp_line
			(start 0.12065 -0.2794)
			(end -0.12065 -0.2794)
			(stroke
				(width 0.1)
				(type default)
			)
			(layer "B.Fab")
		)
		(fp_line
			(start 0.12065 -0.305054)
			(end 0.12065 -0.2794)
			(stroke
				(width 0.1)
				(type default)
			)
			(layer "B.Fab")
		)
		(fp_line
			(start -0.120396 0.3048)
			(end -0.120396 0.2794)
			(stroke
				(width 0.1)
				(type default)
			)
			(layer "B.Fab")
		)
		(fp_line
			(start -0.120396 0.2794)
			(end 0.12065 0.2794)
			(stroke
				(width 0.1)
				(type default)
			)
			(layer "B.Fab")
		)
		(fp_line
			(start -0.12065 -0.2794)
			(end -0.12065 -0.3048)
			(stroke
				(width 0.1)
				(type default)
			)
			(layer "B.Fab")
		)
		(fp_line
			(start -0.12065 -0.3048)
			(end -0.67945 -0.3048)
			(stroke
				(width 0.1)
				(type default)
			)
			(layer "B.Fab")
		)
		(fp_line
			(start -0.67945 0.3048)
			(end -0.120396 0.3048)
			(stroke
				(width 0.1)
				(type default)
			)
			(layer "B.Fab")
		)
		(fp_line
			(start -0.67945 -0.3048)
			(end -0.67945 0.3048)
			(stroke
				(width 0.1)
				(type default)
			)
			(layer "B.Fab")
		)
		(pad "1" smd circle
			(at 0.40005 0)
			(size 0 0)
			(layers "B.Cu" "B.Mask" "B.Paste")
			(net "SMB_PEHPCPU1_GTL_SCL")
		)
		(pad "2" smd circle
			(at -0.40005 0)
			(size 0 0)
			(layers "B.Cu" "B.Mask" "B.Paste")
			(net "SMB_PEHPCPU1_GTL_R_SCL")
		)
	)
)
